FILE_TYPE = MACRO_DRAWING;
SET COLOR_WIRE YELLOW;
SET COLOR_PROP MONO;
SET COLOR_DOT WHITE;
SET COLOR_ARC YELLOW;
SET COLOR_BODY GREEN;
SET COLOR_NOTE MONO;
SET PROP_DISPLAY VALUE;
SET PAGE_NUMBER P29;
FORCEADD TAP..1
R 2
(-5050 3150);
FORCEPROP 3 LASTPIN (-5000 3150) SIG_NAME DMI_CPU0_PCH_RX_C_DN<2>
J 0
(-4990 3160);
DISPLAY 0.659574 (-4990 3160);
PAINT MONO (-4990 3160);
DISPLAY INVISIBLE (-4990 3160);
FORCEPROP 1 LASTPIN (-5000 3150) BN 2
J 2
(-4988 3158);
DISPLAY 0.617021 (-4988 3158);
PAINT PINK (-4988 3158);
FORCEPROP 2 LAST CDS_LIB mstr_standard
J 0
(-5050 3150);
PAINT MONO (-5050 3150);
DISPLAY INVISIBLE (-5050 3150);
FORCEPROP 1 LAST BODY_TYPE PLUMBING
J 2
(-5050 3200);
DISPLAY 1.446809 (-5050 3200);
PAINT GREEN (-5050 3200);
DISPLAY INVISIBLE (-5050 3200);
FORCEPROP 1 LAST HDL_TAP TRUE
J 2
(-5375 3025);
DISPLAY 1.446809 (-5375 3025);
PAINT GREEN (-5375 3025);
DISPLAY INVISIBLE (-5375 3025);
FORCEPROP 1 LAST PATH I10
J 2
(-5048 3150);
DISPLAY 0.872340 (-5048 3150);
PAINT GREEN (-5048 3150);
DISPLAY INVISIBLE (-5048 3150);
FORCEADD TAP..1
R 2
(-5050 3300);
FORCEPROP 3 LASTPIN (-5000 3300) SIG_NAME DMI_CPU0_PCH_RX_C_DP<0>
J 0
(-4990 3310);
DISPLAY 0.659574 (-4990 3310);
PAINT MONO (-4990 3310);
DISPLAY INVISIBLE (-4990 3310);
FORCEPROP 1 LASTPIN (-5000 3300) BN 0
J 2
(-4988 3308);
DISPLAY 0.617021 (-4988 3308);
PAINT PINK (-4988 3308);
FORCEPROP 2 LAST CDS_LIB mstr_standard
J 0
(-5050 3300);
PAINT MONO (-5050 3300);
DISPLAY INVISIBLE (-5050 3300);
FORCEPROP 1 LAST BODY_TYPE PLUMBING
J 2
(-5050 3350);
DISPLAY 1.446809 (-5050 3350);
PAINT GREEN (-5050 3350);
DISPLAY INVISIBLE (-5050 3350);
FORCEPROP 1 LAST HDL_TAP TRUE
J 2
(-5375 3175);
DISPLAY 1.446809 (-5375 3175);
PAINT GREEN (-5375 3175);
DISPLAY INVISIBLE (-5375 3175);
FORCEPROP 1 LAST PATH I11
J 2
(-5048 3300);
DISPLAY 0.872340 (-5048 3300);
PAINT GREEN (-5048 3300);
DISPLAY INVISIBLE (-5048 3300);
FORCEADD TAP..1
R 2
(-5050 3350);
FORCEPROP 3 LASTPIN (-5000 3350) SIG_NAME DMI_CPU0_PCH_RX_C_DP<1>
J 0
(-4990 3360);
DISPLAY 0.659574 (-4990 3360);
PAINT MONO (-4990 3360);
DISPLAY INVISIBLE (-4990 3360);
FORCEPROP 1 LASTPIN (-5000 3350) BN 1
J 2
(-4988 3358);
DISPLAY 0.617021 (-4988 3358);
PAINT PINK (-4988 3358);
FORCEPROP 2 LAST CDS_LIB mstr_standard
J 0
(-5050 3350);
PAINT MONO (-5050 3350);
DISPLAY INVISIBLE (-5050 3350);
FORCEPROP 1 LAST BODY_TYPE PLUMBING
J 2
(-5050 3400);
DISPLAY 1.446809 (-5050 3400);
PAINT GREEN (-5050 3400);
DISPLAY INVISIBLE (-5050 3400);
FORCEPROP 1 LAST HDL_TAP TRUE
J 2
(-5375 3225);
DISPLAY 1.446809 (-5375 3225);
PAINT GREEN (-5375 3225);
DISPLAY INVISIBLE (-5375 3225);
FORCEPROP 1 LAST PATH I12
J 2
(-5048 3350);
DISPLAY 0.872340 (-5048 3350);
PAINT GREEN (-5048 3350);
DISPLAY INVISIBLE (-5048 3350);
FORCEADD TAP..1
R 2
(-5050 3400);
FORCEPROP 3 LASTPIN (-5000 3400) SIG_NAME DMI_CPU0_PCH_RX_C_DP<2>
J 0
(-4990 3410);
DISPLAY 0.659574 (-4990 3410);
PAINT MONO (-4990 3410);
DISPLAY INVISIBLE (-4990 3410);
FORCEPROP 1 LASTPIN (-5000 3400) BN 2
J 2
(-4988 3408);
DISPLAY 0.617021 (-4988 3408);
PAINT PINK (-4988 3408);
FORCEPROP 2 LAST CDS_LIB mstr_standard
J 0
(-5050 3400);
PAINT MONO (-5050 3400);
DISPLAY INVISIBLE (-5050 3400);
FORCEPROP 1 LAST BODY_TYPE PLUMBING
J 2
(-5050 3450);
DISPLAY 1.446809 (-5050 3450);
PAINT GREEN (-5050 3450);
DISPLAY INVISIBLE (-5050 3450);
FORCEPROP 1 LAST HDL_TAP TRUE
J 2
(-5375 3275);
DISPLAY 1.446809 (-5375 3275);
PAINT GREEN (-5375 3275);
DISPLAY INVISIBLE (-5375 3275);
FORCEPROP 1 LAST PATH I13
J 2
(-5048 3400);
DISPLAY 0.872340 (-5048 3400);
PAINT GREEN (-5048 3400);
DISPLAY INVISIBLE (-5048 3400);
FORCEADD TAP..1
R 2
(-5050 3450);
FORCEPROP 3 LASTPIN (-5000 3450) SIG_NAME DMI_CPU0_PCH_RX_C_DP<3>
J 0
(-4990 3460);
DISPLAY 0.659574 (-4990 3460);
PAINT MONO (-4990 3460);
DISPLAY INVISIBLE (-4990 3460);
FORCEPROP 1 LASTPIN (-5000 3450) BN 3
J 2
(-4988 3458);
DISPLAY 0.617021 (-4988 3458);
PAINT PINK (-4988 3458);
FORCEPROP 2 LAST CDS_LIB mstr_standard
J 0
(-5050 3450);
PAINT MONO (-5050 3450);
DISPLAY INVISIBLE (-5050 3450);
FORCEPROP 1 LAST BODY_TYPE PLUMBING
J 2
(-5050 3500);
DISPLAY 1.446809 (-5050 3500);
PAINT GREEN (-5050 3500);
DISPLAY INVISIBLE (-5050 3500);
FORCEPROP 1 LAST HDL_TAP TRUE
J 2
(-5375 3325);
DISPLAY 1.446809 (-5375 3325);
PAINT GREEN (-5375 3325);
DISPLAY INVISIBLE (-5375 3325);
FORCEPROP 1 LAST PATH I14
J 2
(-5048 3450);
DISPLAY 0.872340 (-5048 3450);
PAINT GREEN (-5048 3450);
DISPLAY INVISIBLE (-5048 3450);
FORCEADD TAP..1
(-2750 3100);
FORCEPROP 3 LASTPIN (-2800 3100) SIG_NAME DMI_CPU0_PCH_TX_DN<1>
J 0
(-2790 3110);
DISPLAY 0.659574 (-2790 3110);
PAINT MONO (-2790 3110);
DISPLAY INVISIBLE (-2790 3110);
FORCEPROP 1 LASTPIN (-2800 3100) BN 1
J 0
(-2812 3108);
DISPLAY 0.617021 (-2812 3108);
PAINT PINK (-2812 3108);
FORCEPROP 2 LAST CDS_LIB mstr_standard
J 2
(-2750 3100);
PAINT MONO (-2750 3100);
DISPLAY INVISIBLE (-2750 3100);
FORCEPROP 1 LAST BODY_TYPE PLUMBING
J 0
(-2750 3150);
DISPLAY 1.446809 (-2750 3150);
PAINT GREEN (-2750 3150);
DISPLAY INVISIBLE (-2750 3150);
FORCEPROP 1 LAST HDL_TAP TRUE
J 0
(-2425 2975);
DISPLAY 1.446809 (-2425 2975);
PAINT GREEN (-2425 2975);
DISPLAY INVISIBLE (-2425 2975);
FORCEPROP 1 LAST PATH I16
J 0
(-2752 3100);
DISPLAY 0.872340 (-2752 3100);
PAINT GREEN (-2752 3100);
DISPLAY INVISIBLE (-2752 3100);
FORCEADD TAP..1
(-2750 3050);
FORCEPROP 3 LASTPIN (-2800 3050) SIG_NAME DMI_CPU0_PCH_TX_DN<0>
J 0
(-2790 3060);
DISPLAY 0.659574 (-2790 3060);
PAINT MONO (-2790 3060);
DISPLAY INVISIBLE (-2790 3060);
FORCEPROP 1 LASTPIN (-2800 3050) BN 0
J 0
(-2812 3058);
DISPLAY 0.617021 (-2812 3058);
PAINT PINK (-2812 3058);
FORCEPROP 2 LAST CDS_LIB mstr_standard
J 2
(-2750 3050);
PAINT MONO (-2750 3050);
DISPLAY INVISIBLE (-2750 3050);
FORCEPROP 1 LAST BODY_TYPE PLUMBING
J 0
(-2750 3100);
DISPLAY 1.446809 (-2750 3100);
PAINT GREEN (-2750 3100);
DISPLAY INVISIBLE (-2750 3100);
FORCEPROP 1 LAST HDL_TAP TRUE
J 0
(-2425 2925);
DISPLAY 1.446809 (-2425 2925);
PAINT GREEN (-2425 2925);
DISPLAY INVISIBLE (-2425 2925);
FORCEPROP 1 LAST PATH I17
J 0
(-2752 3050);
DISPLAY 0.872340 (-2752 3050);
PAINT GREEN (-2752 3050);
DISPLAY INVISIBLE (-2752 3050);
FORCEADD TAP..1
(-2750 3200);
FORCEPROP 3 LASTPIN (-2800 3200) SIG_NAME DMI_CPU0_PCH_TX_DN<3>
J 0
(-2790 3210);
DISPLAY 0.659574 (-2790 3210);
PAINT MONO (-2790 3210);
DISPLAY INVISIBLE (-2790 3210);
FORCEPROP 1 LASTPIN (-2800 3200) BN 3
J 0
(-2812 3208);
DISPLAY 0.617021 (-2812 3208);
PAINT PINK (-2812 3208);
FORCEPROP 2 LAST CDS_LIB mstr_standard
J 2
(-2750 3200);
PAINT MONO (-2750 3200);
DISPLAY INVISIBLE (-2750 3200);
FORCEPROP 1 LAST BODY_TYPE PLUMBING
J 0
(-2750 3250);
DISPLAY 1.446809 (-2750 3250);
PAINT GREEN (-2750 3250);
DISPLAY INVISIBLE (-2750 3250);
FORCEPROP 1 LAST HDL_TAP TRUE
J 0
(-2425 3075);
DISPLAY 1.446809 (-2425 3075);
PAINT GREEN (-2425 3075);
DISPLAY INVISIBLE (-2425 3075);
FORCEPROP 1 LAST PATH I18
J 0
(-2752 3200);
DISPLAY 0.872340 (-2752 3200);
PAINT GREEN (-2752 3200);
DISPLAY INVISIBLE (-2752 3200);
FORCEADD TAP..1
(-2750 3150);
FORCEPROP 3 LASTPIN (-2800 3150) SIG_NAME DMI_CPU0_PCH_TX_DN<2>
J 0
(-2790 3160);
DISPLAY 0.659574 (-2790 3160);
PAINT MONO (-2790 3160);
DISPLAY INVISIBLE (-2790 3160);
FORCEPROP 1 LASTPIN (-2800 3150) BN 2
J 0
(-2812 3158);
DISPLAY 0.617021 (-2812 3158);
PAINT PINK (-2812 3158);
FORCEPROP 2 LAST CDS_LIB mstr_standard
J 2
(-2750 3150);
PAINT MONO (-2750 3150);
DISPLAY INVISIBLE (-2750 3150);
FORCEPROP 1 LAST BODY_TYPE PLUMBING
J 0
(-2750 3200);
DISPLAY 1.446809 (-2750 3200);
PAINT GREEN (-2750 3200);
DISPLAY INVISIBLE (-2750 3200);
FORCEPROP 1 LAST HDL_TAP TRUE
J 0
(-2425 3025);
DISPLAY 1.446809 (-2425 3025);
PAINT GREEN (-2425 3025);
DISPLAY INVISIBLE (-2425 3025);
FORCEPROP 1 LAST PATH I19
J 0
(-2752 3150);
DISPLAY 0.872340 (-2752 3150);
PAINT GREEN (-2752 3150);
DISPLAY INVISIBLE (-2752 3150);
FORCEADD TAP..1
(-2750 3300);
FORCEPROP 3 LASTPIN (-2800 3300) SIG_NAME DMI_CPU0_PCH_TX_DP<0>
J 0
(-2790 3310);
DISPLAY 0.659574 (-2790 3310);
PAINT MONO (-2790 3310);
DISPLAY INVISIBLE (-2790 3310);
FORCEPROP 1 LASTPIN (-2800 3300) BN 0
J 0
(-2812 3308);
DISPLAY 0.617021 (-2812 3308);
PAINT PINK (-2812 3308);
FORCEPROP 2 LAST CDS_LIB mstr_standard
J 2
(-2750 3300);
PAINT MONO (-2750 3300);
DISPLAY INVISIBLE (-2750 3300);
FORCEPROP 1 LAST BODY_TYPE PLUMBING
J 0
(-2750 3350);
DISPLAY 1.446809 (-2750 3350);
PAINT GREEN (-2750 3350);
DISPLAY INVISIBLE (-2750 3350);
FORCEPROP 1 LAST HDL_TAP TRUE
J 0
(-2425 3175);
DISPLAY 1.446809 (-2425 3175);
PAINT GREEN (-2425 3175);
DISPLAY INVISIBLE (-2425 3175);
FORCEPROP 1 LAST PATH I20
J 0
(-2752 3300);
DISPLAY 0.872340 (-2752 3300);
PAINT GREEN (-2752 3300);
DISPLAY INVISIBLE (-2752 3300);
FORCEADD TAP..1
(-2750 3400);
FORCEPROP 3 LASTPIN (-2800 3400) SIG_NAME DMI_CPU0_PCH_TX_DP<2>
J 0
(-2790 3410);
DISPLAY 0.659574 (-2790 3410);
PAINT MONO (-2790 3410);
DISPLAY INVISIBLE (-2790 3410);
FORCEPROP 1 LASTPIN (-2800 3400) BN 2
J 0
(-2812 3408);
DISPLAY 0.617021 (-2812 3408);
PAINT PINK (-2812 3408);
FORCEPROP 2 LAST CDS_LIB mstr_standard
J 2
(-2750 3400);
PAINT MONO (-2750 3400);
DISPLAY INVISIBLE (-2750 3400);
FORCEPROP 1 LAST BODY_TYPE PLUMBING
J 0
(-2750 3450);
DISPLAY 1.446809 (-2750 3450);
PAINT GREEN (-2750 3450);
DISPLAY INVISIBLE (-2750 3450);
FORCEPROP 1 LAST HDL_TAP TRUE
J 0
(-2425 3275);
DISPLAY 1.446809 (-2425 3275);
PAINT GREEN (-2425 3275);
DISPLAY INVISIBLE (-2425 3275);
FORCEPROP 1 LAST PATH I21
J 0
(-2752 3400);
DISPLAY 0.872340 (-2752 3400);
PAINT GREEN (-2752 3400);
DISPLAY INVISIBLE (-2752 3400);
FORCEADD TAP..1
(-2750 3350);
FORCEPROP 3 LASTPIN (-2800 3350) SIG_NAME DMI_CPU0_PCH_TX_DP<1>
J 0
(-2790 3360);
DISPLAY 0.659574 (-2790 3360);
PAINT MONO (-2790 3360);
DISPLAY INVISIBLE (-2790 3360);
FORCEPROP 1 LASTPIN (-2800 3350) BN 1
J 0
(-2812 3358);
DISPLAY 0.617021 (-2812 3358);
PAINT PINK (-2812 3358);
FORCEPROP 2 LAST CDS_LIB mstr_standard
J 2
(-2750 3350);
PAINT MONO (-2750 3350);
DISPLAY INVISIBLE (-2750 3350);
FORCEPROP 1 LAST BODY_TYPE PLUMBING
J 0
(-2750 3400);
DISPLAY 1.446809 (-2750 3400);
PAINT GREEN (-2750 3400);
DISPLAY INVISIBLE (-2750 3400);
FORCEPROP 1 LAST HDL_TAP TRUE
J 0
(-2425 3225);
DISPLAY 1.446809 (-2425 3225);
PAINT GREEN (-2425 3225);
DISPLAY INVISIBLE (-2425 3225);
FORCEPROP 1 LAST PATH I22
J 0
(-2752 3350);
DISPLAY 0.872340 (-2752 3350);
PAINT GREEN (-2752 3350);
DISPLAY INVISIBLE (-2752 3350);
FORCEADD TAP..1
(-2750 3450);
FORCEPROP 3 LASTPIN (-2800 3450) SIG_NAME DMI_CPU0_PCH_TX_DP<3>
J 0
(-2790 3460);
DISPLAY 0.659574 (-2790 3460);
PAINT MONO (-2790 3460);
DISPLAY INVISIBLE (-2790 3460);
FORCEPROP 1 LASTPIN (-2800 3450) BN 3
J 0
(-2812 3458);
DISPLAY 0.617021 (-2812 3458);
PAINT PINK (-2812 3458);
FORCEPROP 2 LAST CDS_LIB mstr_standard
J 2
(-2750 3450);
PAINT MONO (-2750 3450);
DISPLAY INVISIBLE (-2750 3450);
FORCEPROP 1 LAST BODY_TYPE PLUMBING
J 0
(-2750 3500);
DISPLAY 1.446809 (-2750 3500);
PAINT GREEN (-2750 3500);
DISPLAY INVISIBLE (-2750 3500);
FORCEPROP 1 LAST HDL_TAP TRUE
J 0
(-2425 3325);
DISPLAY 1.446809 (-2425 3325);
PAINT GREEN (-2425 3325);
DISPLAY INVISIBLE (-2425 3325);
FORCEPROP 1 LAST PATH I23
J 0
(-2752 3450);
DISPLAY 0.872340 (-2752 3450);
PAINT GREEN (-2752 3450);
DISPLAY INVISIBLE (-2752 3450);
FORCEADD OFFPAGE..2
(-1650 3250);
FORCEPROP 2 LAST $XR0 129 
J 0
(-1461 3250);
DISPLAY 0.638298 (-1461 3250);
PAINT MONO (-1461 3250);
FORCEPROP 2 LAST PATH I25
J 0
(-1475 3325);
DISPLAY 1.021277 (-1475 3325);
PAINT ORANGE (-1475 3325);
DISPLAY INVISIBLE (-1475 3325);
FORCEPROP 1 LAST COMMENT_BODY TRUE
J 0
(-1695 3155);
DISPLAY 1.170213 (-1695 3155);
PAINT GREEN (-1695 3155);
DISPLAY INVISIBLE (-1695 3155);
FORCEPROP 1 LAST OFFPAGE TRUE
J 0
(-1325 3125);
DISPLAY 1.170213 (-1325 3125);
PAINT GREEN (-1325 3125);
DISPLAY INVISIBLE (-1325 3125);
FORCEPROP 2 LAST CDS_LIB mstr_standard
J 0
(-1650 3250);
PAINT MONO (-1650 3250);
DISPLAY INVISIBLE (-1650 3250);
FORCEADD OFFPAGE..2
(-1650 3500);
FORCEPROP 2 LAST $XR0 129 
J 0
(-1461 3500);
DISPLAY 0.638298 (-1461 3500);
PAINT MONO (-1461 3500);
FORCEPROP 2 LAST PATH I26
J 0
(-1475 3575);
DISPLAY 1.021277 (-1475 3575);
PAINT ORANGE (-1475 3575);
DISPLAY INVISIBLE (-1475 3575);
FORCEPROP 1 LAST COMMENT_BODY TRUE
J 0
(-1695 3405);
DISPLAY 1.170213 (-1695 3405);
PAINT GREEN (-1695 3405);
DISPLAY INVISIBLE (-1695 3405);
FORCEPROP 1 LAST OFFPAGE TRUE
J 0
(-1325 3375);
DISPLAY 1.170213 (-1325 3375);
PAINT GREEN (-1325 3375);
DISPLAY INVISIBLE (-1325 3375);
FORCEPROP 2 LAST CDS_LIB mstr_standard
J 0
(-1650 3500);
PAINT MONO (-1650 3500);
DISPLAY INVISIBLE (-1650 3500);
FORCEADD OFFPAGE..1
(-6150 2400);
FORCEPROP 2 LAST $XR1 63 
J 0
(-6492 2400);
DISPLAY 0.638298 (-6492 2400);
PAINT MONO (-6492 2400);
FORCEPROP 2 LAST $XR0 113 
J 0
(-6402 2400);
DISPLAY 0.638298 (-6402 2400);
PAINT MONO (-6402 2400);
FORCEPROP 2 LAST PATH I27
J 0
(-6100 2475);
DISPLAY 1.021277 (-6100 2475);
PAINT ORANGE (-6100 2475);
DISPLAY INVISIBLE (-6100 2475);
FORCEPROP 1 LAST COMMENT_BODY TRUE
J 0
(-6025 2300);
DISPLAY 0.872340 (-6025 2300);
PAINT GREEN (-6025 2300);
DISPLAY INVISIBLE (-6025 2300);
FORCEPROP 1 LAST OFFPAGE TRUE
J 0
(-5825 2275);
DISPLAY 0.872340 (-5825 2275);
PAINT GREEN (-5825 2275);
DISPLAY INVISIBLE (-5825 2275);
FORCEPROP 2 LAST CDS_LIB mstr_standard
J 0
(-6150 2400);
PAINT ORANGE (-6150 2400);
DISPLAY INVISIBLE (-6150 2400);
FORCEADD OFFPAGE..1
(-6150 2350);
FORCEPROP 2 LAST $XR0 113 
J 0
(-6402 2350);
DISPLAY 0.638298 (-6402 2350);
PAINT MONO (-6402 2350);
FORCEPROP 2 LAST PATH I28
J 0
(-6100 2425);
DISPLAY 1.021277 (-6100 2425);
PAINT ORANGE (-6100 2425);
DISPLAY INVISIBLE (-6100 2425);
FORCEPROP 1 LAST COMMENT_BODY TRUE
J 0
(-6025 2250);
DISPLAY 1.170213 (-6025 2250);
PAINT GREEN (-6025 2250);
DISPLAY INVISIBLE (-6025 2250);
FORCEPROP 1 LAST OFFPAGE TRUE
J 0
(-5825 2225);
DISPLAY 1.170213 (-5825 2225);
PAINT GREEN (-5825 2225);
DISPLAY INVISIBLE (-5825 2225);
FORCEPROP 2 LAST CDS_LIB mstr_standard
J 0
(-6150 2350);
PAINT ORANGE (-6150 2350);
DISPLAY INVISIBLE (-6150 2350);
FORCEADD OFFPAGE..1
(-6150 2300);
FORCEPROP 2 LAST $XR1 63 
J 0
(-6492 2300);
DISPLAY 0.638298 (-6492 2300);
PAINT MONO (-6492 2300);
FORCEPROP 2 LAST $XR0 113 
J 0
(-6402 2300);
DISPLAY 0.638298 (-6402 2300);
PAINT MONO (-6402 2300);
FORCEPROP 2 LAST PATH I29
J 0
(-6100 2375);
DISPLAY 1.021277 (-6100 2375);
PAINT ORANGE (-6100 2375);
DISPLAY INVISIBLE (-6100 2375);
FORCEPROP 1 LAST COMMENT_BODY TRUE
J 0
(-6025 2200);
DISPLAY 0.872340 (-6025 2200);
PAINT GREEN (-6025 2200);
DISPLAY INVISIBLE (-6025 2200);
FORCEPROP 1 LAST OFFPAGE TRUE
J 0
(-5825 2175);
DISPLAY 0.872340 (-5825 2175);
PAINT GREEN (-5825 2175);
DISPLAY INVISIBLE (-5825 2175);
FORCEPROP 2 LAST CDS_LIB mstr_standard
J 0
(-6150 2300);
PAINT ORANGE (-6150 2300);
DISPLAY INVISIBLE (-6150 2300);
FORCEADD OFFPAGE..2
(-1650 2250);
FORCEPROP 2 LAST $XR0 113 
J 0
(-1461 2250);
DISPLAY 0.638298 (-1461 2250);
PAINT MONO (-1461 2250);
FORCEPROP 2 LAST PATH I31
J 0
(-1475 2325);
DISPLAY 1.021277 (-1475 2325);
PAINT ORANGE (-1475 2325);
DISPLAY INVISIBLE (-1475 2325);
FORCEPROP 1 LAST COMMENT_BODY TRUE
J 0
(-1695 2155);
DISPLAY 1.170213 (-1695 2155);
PAINT GREEN (-1695 2155);
DISPLAY INVISIBLE (-1695 2155);
FORCEPROP 1 LAST OFFPAGE TRUE
J 0
(-1325 2125);
DISPLAY 1.170213 (-1325 2125);
PAINT GREEN (-1325 2125);
DISPLAY INVISIBLE (-1325 2125);
FORCEPROP 2 LAST CDS_LIB mstr_standard
J 0
(-1650 2250);
PAINT ORANGE (-1650 2250);
DISPLAY INVISIBLE (-1650 2250);
FORCEADD OFFPAGE..1
R 2
(-1650 2950);
FORCEPROP 2 LAST $XR0 103 
J 0
(-1464 2950);
DISPLAY 0.638298 (-1464 2950);
PAINT MONO (-1464 2950);
FORCEPROP 2 LAST PATH I35
J 0
(-1475 3025);
DISPLAY 1.021277 (-1475 3025);
PAINT ORANGE (-1475 3025);
DISPLAY INVISIBLE (-1475 3025);
FORCEPROP 1 LAST COMMENT_BODY TRUE
J 2
(-1775 2850);
DISPLAY 0.872340 (-1775 2850);
PAINT GREEN (-1775 2850);
DISPLAY INVISIBLE (-1775 2850);
FORCEPROP 1 LAST OFFPAGE TRUE
J 2
(-1975 2825);
DISPLAY 0.872340 (-1975 2825);
PAINT GREEN (-1975 2825);
DISPLAY INVISIBLE (-1975 2825);
FORCEPROP 2 LAST CDS_LIB mstr_standard
J 0
(-1650 2950);
PAINT ORANGE (-1650 2950);
DISPLAY INVISIBLE (-1650 2950);
FORCEADD OFFPAGE..1
R 2
(-1650 2900);
FORCEPROP 2 LAST $XR0 103 
J 0
(-1464 2900);
DISPLAY 0.638298 (-1464 2900);
PAINT MONO (-1464 2900);
FORCEPROP 2 LAST PATH I36
J 0
(-1475 2975);
DISPLAY 1.021277 (-1475 2975);
PAINT ORANGE (-1475 2975);
DISPLAY INVISIBLE (-1475 2975);
FORCEPROP 1 LAST COMMENT_BODY TRUE
J 2
(-1775 2800);
DISPLAY 0.872340 (-1775 2800);
PAINT GREEN (-1775 2800);
DISPLAY INVISIBLE (-1775 2800);
FORCEPROP 1 LAST OFFPAGE TRUE
J 2
(-1975 2775);
DISPLAY 0.872340 (-1975 2775);
PAINT GREEN (-1975 2775);
DISPLAY INVISIBLE (-1975 2775);
FORCEPROP 2 LAST CDS_LIB mstr_standard
J 0
(-1650 2900);
PAINT ORANGE (-1650 2900);
DISPLAY INVISIBLE (-1650 2900);
FORCEADD OFFPAGE..1
(-6150 2950);
FORCEPROP 2 LAST $XR0 104 
J 0
(-6402 2950);
DISPLAY 0.638298 (-6402 2950);
PAINT MONO (-6402 2950);
FORCEPROP 2 LAST PATH I40
J 0
(-6100 3025);
DISPLAY 1.021277 (-6100 3025);
PAINT ORANGE (-6100 3025);
DISPLAY INVISIBLE (-6100 3025);
FORCEPROP 1 LAST COMMENT_BODY TRUE
J 0
(-6025 2850);
DISPLAY 0.872340 (-6025 2850);
PAINT GREEN (-6025 2850);
DISPLAY INVISIBLE (-6025 2850);
FORCEPROP 1 LAST OFFPAGE TRUE
J 0
(-5825 2825);
DISPLAY 0.872340 (-5825 2825);
PAINT GREEN (-5825 2825);
DISPLAY INVISIBLE (-5825 2825);
FORCEPROP 2 LAST CDS_LIB mstr_standard
J 0
(-6150 2950);
PAINT ORANGE (-6150 2950);
DISPLAY INVISIBLE (-6150 2950);
FORCEADD OFFPAGE..1
(-6150 2900);
FORCEPROP 2 LAST $XR0 104 
J 0
(-6402 2900);
DISPLAY 0.638298 (-6402 2900);
PAINT MONO (-6402 2900);
FORCEPROP 2 LAST PATH I41
J 0
(-6100 2975);
DISPLAY 1.021277 (-6100 2975);
PAINT ORANGE (-6100 2975);
DISPLAY INVISIBLE (-6100 2975);
FORCEPROP 1 LAST COMMENT_BODY TRUE
J 0
(-6025 2800);
DISPLAY 0.872340 (-6025 2800);
PAINT GREEN (-6025 2800);
DISPLAY INVISIBLE (-6025 2800);
FORCEPROP 1 LAST OFFPAGE TRUE
J 0
(-5825 2775);
DISPLAY 0.872340 (-5825 2775);
PAINT GREEN (-5825 2775);
DISPLAY INVISIBLE (-5825 2775);
FORCEPROP 2 LAST CDS_LIB mstr_standard
J 0
(-6150 2900);
PAINT ORANGE (-6150 2900);
DISPLAY INVISIBLE (-6150 2900);
FORCEADD OFFPAGE..1
R 2
(-1650 2350);
FORCEPROP 2 LAST $XR1 192 
J 0
(-924 2350);
DISPLAY 0.638298 (-924 2350);
PAINT MONO (-924 2350);
FORCEPROP 2 LAST $XR0 190 
J 0
(-1044 2350);
DISPLAY 0.638298 (-1044 2350);
PAINT MONO (-1044 2350);
FORCEPROP 2 LAST CDS_LIB mstr_standard
J 0
(-1650 2350);
PAINT MONO (-1650 2350);
DISPLAY INVISIBLE (-1650 2350);
FORCEPROP 1 LAST OFFPAGE TRUE
J 2
(-1975 2225);
DISPLAY 0.872340 (-1975 2225);
PAINT GREEN (-1975 2225);
DISPLAY INVISIBLE (-1975 2225);
FORCEPROP 1 LAST COMMENT_BODY TRUE
J 2
(-1775 2250);
DISPLAY 0.872340 (-1775 2250);
PAINT GREEN (-1775 2250);
DISPLAY INVISIBLE (-1775 2250);
FORCEPROP 2 LAST PATH I42
J 0
(-1475 2425);
DISPLAY 1.021277 (-1475 2425);
PAINT ORANGE (-1475 2425);
DISPLAY INVISIBLE (-1475 2425);
FORCEADD OFFPAGE..5
(-6150 2800);
FORCEPROP 2 LAST $XR0 91 
J 0
(-6374 2800);
DISPLAY 0.638298 (-6374 2800);
PAINT MONO (-6374 2800);
FORCEPROP 2 LAST PATH I43
J 0
(-6100 2875);
DISPLAY 1.021277 (-6100 2875);
PAINT ORANGE (-6100 2875);
DISPLAY INVISIBLE (-6100 2875);
FORCEPROP 1 LAST COMMENT_BODY TRUE
J 0
(-6050 2725);
DISPLAY 0.872340 (-6050 2725);
PAINT GREEN (-6050 2725);
DISPLAY INVISIBLE (-6050 2725);
FORCEPROP 1 LAST OFFPAGE TRUE
J 0
(-5825 2675);
DISPLAY 0.872340 (-5825 2675);
PAINT GREEN (-5825 2675);
DISPLAY INVISIBLE (-5825 2675);
FORCEPROP 2 LAST CDS_LIB mstr_standard
J 0
(-6150 2800);
PAINT MONO (-6150 2800);
DISPLAY INVISIBLE (-6150 2800);
FORCEADD OFFPAGE..1
(-6150 2750);
FORCEPROP 2 LAST $XR0 91 
J 0
(-6371 2750);
DISPLAY 0.638298 (-6371 2750);
PAINT MONO (-6371 2750);
FORCEPROP 2 LAST PATH I44
J 0
(-6100 2825);
DISPLAY 1.021277 (-6100 2825);
PAINT ORANGE (-6100 2825);
DISPLAY INVISIBLE (-6100 2825);
FORCEPROP 1 LAST COMMENT_BODY TRUE
J 0
(-6025 2650);
DISPLAY 0.872340 (-6025 2650);
PAINT GREEN (-6025 2650);
DISPLAY INVISIBLE (-6025 2650);
FORCEPROP 1 LAST OFFPAGE TRUE
J 0
(-5825 2625);
DISPLAY 0.872340 (-5825 2625);
PAINT GREEN (-5825 2625);
DISPLAY INVISIBLE (-5825 2625);
FORCEPROP 2 LAST CDS_LIB mstr_standard
J 0
(-6150 2750);
PAINT MONO (-6150 2750);
DISPLAY INVISIBLE (-6150 2750);
FORCEADD OFFPAGE..1
(-6150 2650);
FORCEPROP 2 LAST $XR0 91 
J 0
(-6371 2650);
DISPLAY 0.638298 (-6371 2650);
PAINT MONO (-6371 2650);
FORCEPROP 2 LAST PATH I45
J 0
(-6100 2725);
DISPLAY 1.021277 (-6100 2725);
PAINT ORANGE (-6100 2725);
DISPLAY INVISIBLE (-6100 2725);
FORCEPROP 1 LAST COMMENT_BODY TRUE
J 0
(-6025 2550);
DISPLAY 0.872340 (-6025 2550);
PAINT GREEN (-6025 2550);
DISPLAY INVISIBLE (-6025 2550);
FORCEPROP 1 LAST OFFPAGE TRUE
J 0
(-5825 2525);
DISPLAY 0.872340 (-5825 2525);
PAINT GREEN (-5825 2525);
DISPLAY INVISIBLE (-5825 2525);
FORCEPROP 2 LAST CDS_LIB mstr_standard
J 0
(-6150 2650);
PAINT MONO (-6150 2650);
DISPLAY INVISIBLE (-6150 2650);
FORCEADD OFFPAGE..5
(-6150 2700);
FORCEPROP 2 LAST $XR0 91 
J 0
(-6374 2700);
DISPLAY 0.638298 (-6374 2700);
PAINT MONO (-6374 2700);
FORCEPROP 2 LAST PATH I46
J 0
(-6100 2775);
DISPLAY 1.021277 (-6100 2775);
PAINT ORANGE (-6100 2775);
DISPLAY INVISIBLE (-6100 2775);
FORCEPROP 1 LAST COMMENT_BODY TRUE
J 0
(-6050 2625);
DISPLAY 0.872340 (-6050 2625);
PAINT GREEN (-6050 2625);
DISPLAY INVISIBLE (-6050 2625);
FORCEPROP 1 LAST OFFPAGE TRUE
J 0
(-5825 2575);
DISPLAY 0.872340 (-5825 2575);
PAINT GREEN (-5825 2575);
DISPLAY INVISIBLE (-5825 2575);
FORCEPROP 2 LAST CDS_LIB mstr_standard
J 0
(-6150 2700);
PAINT MONO (-6150 2700);
DISPLAY INVISIBLE (-6150 2700);
FORCEADD OFFPAGE..5
(-6150 2550);
FORCEPROP 2 LAST $XR0 91 
J 0
(-6374 2550);
DISPLAY 0.638298 (-6374 2550);
PAINT MONO (-6374 2550);
FORCEPROP 2 LAST PATH I47
J 0
(-6100 2625);
DISPLAY 1.021277 (-6100 2625);
PAINT ORANGE (-6100 2625);
DISPLAY INVISIBLE (-6100 2625);
FORCEPROP 1 LAST COMMENT_BODY TRUE
J 0
(-6050 2475);
DISPLAY 0.872340 (-6050 2475);
PAINT GREEN (-6050 2475);
DISPLAY INVISIBLE (-6050 2475);
FORCEPROP 1 LAST OFFPAGE TRUE
J 0
(-5825 2425);
DISPLAY 0.872340 (-5825 2425);
PAINT GREEN (-5825 2425);
DISPLAY INVISIBLE (-5825 2425);
FORCEPROP 2 LAST CDS_LIB mstr_standard
J 0
(-6150 2550);
PAINT MONO (-6150 2550);
DISPLAY INVISIBLE (-6150 2550);
FORCEADD OFFPAGE..3
R 2
(-6150 2500);
FORCEPROP 2 LAST $XR0 91 
J 0
(-6429 2500);
DISPLAY 0.638298 (-6429 2500);
PAINT MONO (-6429 2500);
FORCEPROP 2 LAST PATH I48
J 2
(-6200 2575);
DISPLAY 1.021277 (-6200 2575);
PAINT ORANGE (-6200 2575);
DISPLAY INVISIBLE (-6200 2575);
FORCEPROP 1 LAST COMMENT_BODY TRUE
J 2
(-6100 2400);
DISPLAY 0.872340 (-6100 2400);
PAINT GREEN (-6100 2400);
DISPLAY INVISIBLE (-6100 2400);
FORCEPROP 1 LAST OFFPAGE TRUE
J 2
(-6475 2375);
DISPLAY 0.872340 (-6475 2375);
PAINT GREEN (-6475 2375);
DISPLAY INVISIBLE (-6475 2375);
FORCEPROP 2 LAST CDS_LIB mstr_standard
J 2
(-6150 2500);
PAINT MONO (-6150 2500);
DISPLAY INVISIBLE (-6150 2500);
FORCEADD OFFPAGE..1
R 2
(-1650 2750);
FORCEPROP 2 LAST $XR0 91 
J 0
(-1464 2750);
DISPLAY 0.638298 (-1464 2750);
PAINT MONO (-1464 2750);
FORCEPROP 2 LAST PATH I49
J 0
(-1475 2825);
DISPLAY 1.021277 (-1475 2825);
PAINT ORANGE (-1475 2825);
DISPLAY INVISIBLE (-1475 2825);
FORCEPROP 1 LAST COMMENT_BODY TRUE
J 2
(-1775 2650);
DISPLAY 0.872340 (-1775 2650);
PAINT GREEN (-1775 2650);
DISPLAY INVISIBLE (-1775 2650);
FORCEPROP 1 LAST OFFPAGE TRUE
J 2
(-1975 2625);
DISPLAY 0.872340 (-1975 2625);
PAINT GREEN (-1975 2625);
DISPLAY INVISIBLE (-1975 2625);
FORCEPROP 2 LAST CDS_LIB mstr_standard
J 0
(-1650 2750);
PAINT MONO (-1650 2750);
DISPLAY INVISIBLE (-1650 2750);
FORCEADD OFFPAGE..1
(-6150 3250);
FORCEPROP 2 LAST $XR0 129 
J 0
(-6402 3250);
DISPLAY 0.638298 (-6402 3250);
PAINT MONO (-6402 3250);
FORCEPROP 2 LAST PATH I5
J 0
(-6100 3325);
DISPLAY 1.021277 (-6100 3325);
PAINT ORANGE (-6100 3325);
DISPLAY INVISIBLE (-6100 3325);
FORCEPROP 1 LAST COMMENT_BODY TRUE
J 0
(-6025 3150);
DISPLAY 1.170213 (-6025 3150);
PAINT GREEN (-6025 3150);
DISPLAY INVISIBLE (-6025 3150);
FORCEPROP 1 LAST OFFPAGE TRUE
J 0
(-5825 3125);
DISPLAY 1.170213 (-5825 3125);
PAINT GREEN (-5825 3125);
DISPLAY INVISIBLE (-5825 3125);
FORCEPROP 2 LAST CDS_LIB mstr_standard
J 0
(-6150 3250);
PAINT MONO (-6150 3250);
DISPLAY INVISIBLE (-6150 3250);
FORCEADD OFFPAGE..1
R 2
(-1650 2650);
FORCEPROP 2 LAST $XR0 91 
J 0
(-1464 2650);
DISPLAY 0.638298 (-1464 2650);
PAINT MONO (-1464 2650);
FORCEPROP 2 LAST PATH I50
J 0
(-1475 2725);
DISPLAY 1.021277 (-1475 2725);
PAINT ORANGE (-1475 2725);
DISPLAY INVISIBLE (-1475 2725);
FORCEPROP 1 LAST COMMENT_BODY TRUE
J 2
(-1775 2550);
DISPLAY 0.872340 (-1775 2550);
PAINT GREEN (-1775 2550);
DISPLAY INVISIBLE (-1775 2550);
FORCEPROP 1 LAST OFFPAGE TRUE
J 2
(-1975 2525);
DISPLAY 0.872340 (-1975 2525);
PAINT GREEN (-1975 2525);
DISPLAY INVISIBLE (-1975 2525);
FORCEPROP 2 LAST CDS_LIB mstr_standard
J 0
(-1650 2650);
PAINT MONO (-1650 2650);
DISPLAY INVISIBLE (-1650 2650);
FORCEADD OFFPAGE..2
(-1650 2800);
FORCEPROP 2 LAST $XR0 91 
J 0
(-1461 2800);
DISPLAY 0.638298 (-1461 2800);
PAINT MONO (-1461 2800);
FORCEPROP 2 LAST PATH I51
J 0
(-1475 2875);
DISPLAY 1.021277 (-1475 2875);
PAINT ORANGE (-1475 2875);
DISPLAY INVISIBLE (-1475 2875);
FORCEPROP 1 LAST COMMENT_BODY TRUE
J 0
(-1695 2705);
DISPLAY 1.170213 (-1695 2705);
PAINT GREEN (-1695 2705);
DISPLAY INVISIBLE (-1695 2705);
FORCEPROP 1 LAST OFFPAGE TRUE
J 0
(-1325 2675);
DISPLAY 1.170213 (-1325 2675);
PAINT GREEN (-1325 2675);
DISPLAY INVISIBLE (-1325 2675);
FORCEPROP 2 LAST CDS_LIB mstr_standard
J 0
(-1650 2800);
PAINT MONO (-1650 2800);
DISPLAY INVISIBLE (-1650 2800);
FORCEADD OFFPAGE..2
(-1650 2700);
FORCEPROP 2 LAST $XR0 91 
J 0
(-1461 2700);
DISPLAY 0.638298 (-1461 2700);
PAINT MONO (-1461 2700);
FORCEPROP 2 LAST PATH I52
J 0
(-1475 2775);
DISPLAY 1.021277 (-1475 2775);
PAINT ORANGE (-1475 2775);
DISPLAY INVISIBLE (-1475 2775);
FORCEPROP 1 LAST COMMENT_BODY TRUE
J 0
(-1695 2605);
DISPLAY 1.170213 (-1695 2605);
PAINT GREEN (-1695 2605);
DISPLAY INVISIBLE (-1695 2605);
FORCEPROP 1 LAST OFFPAGE TRUE
J 0
(-1325 2575);
DISPLAY 1.170213 (-1325 2575);
PAINT GREEN (-1325 2575);
DISPLAY INVISIBLE (-1325 2575);
FORCEPROP 2 LAST CDS_LIB mstr_standard
J 0
(-1650 2700);
PAINT MONO (-1650 2700);
DISPLAY INVISIBLE (-1650 2700);
FORCEADD OFFPAGE..2
(-1650 2550);
FORCEPROP 2 LAST $XR0 91 
J 0
(-1461 2550);
DISPLAY 0.638298 (-1461 2550);
PAINT MONO (-1461 2550);
FORCEPROP 2 LAST PATH I53
J 0
(-1475 2625);
DISPLAY 1.021277 (-1475 2625);
PAINT ORANGE (-1475 2625);
DISPLAY INVISIBLE (-1475 2625);
FORCEPROP 1 LAST COMMENT_BODY TRUE
J 0
(-1695 2455);
DISPLAY 1.170213 (-1695 2455);
PAINT GREEN (-1695 2455);
DISPLAY INVISIBLE (-1695 2455);
FORCEPROP 1 LAST OFFPAGE TRUE
J 0
(-1325 2425);
DISPLAY 1.170213 (-1325 2425);
PAINT GREEN (-1325 2425);
DISPLAY INVISIBLE (-1325 2425);
FORCEPROP 2 LAST CDS_LIB mstr_standard
J 0
(-1650 2550);
PAINT MONO (-1650 2550);
DISPLAY INVISIBLE (-1650 2550);
FORCEADD OFFPAGE..3
(-1650 2500);
FORCEPROP 2 LAST $XR0 91 
J 0
(-1436 2500);
DISPLAY 0.638298 (-1436 2500);
PAINT MONO (-1436 2500);
FORCEPROP 2 LAST PATH I54
J 0
(-1475 2575);
DISPLAY 1.021277 (-1475 2575);
PAINT ORANGE (-1475 2575);
DISPLAY INVISIBLE (-1475 2575);
FORCEPROP 1 LAST COMMENT_BODY TRUE
J 0
(-1700 2400);
DISPLAY 0.872340 (-1700 2400);
PAINT GREEN (-1700 2400);
DISPLAY INVISIBLE (-1700 2400);
FORCEPROP 1 LAST OFFPAGE TRUE
J 0
(-1325 2375);
DISPLAY 0.872340 (-1325 2375);
PAINT GREEN (-1325 2375);
DISPLAY INVISIBLE (-1325 2375);
FORCEPROP 2 LAST CDS_LIB mstr_standard
J 0
(-1650 2500);
PAINT MONO (-1650 2500);
DISPLAY INVISIBLE (-1650 2500);
FORCEADD OFFPAGE..1
(-6150 2250);
FORCEPROP 2 LAST $XR1 63 
J 0
(-6492 2250);
DISPLAY 0.638298 (-6492 2250);
PAINT MONO (-6492 2250);
FORCEPROP 2 LAST $XR0 113 
J 0
(-6402 2250);
DISPLAY 0.638298 (-6402 2250);
PAINT MONO (-6402 2250);
FORCEPROP 2 LAST PATH I58
J 0
(-6100 2325);
DISPLAY 1.021277 (-6100 2325);
PAINT ORANGE (-6100 2325);
DISPLAY INVISIBLE (-6100 2325);
FORCEPROP 1 LAST COMMENT_BODY TRUE
J 0
(-6025 2150);
DISPLAY 0.872340 (-6025 2150);
PAINT GREEN (-6025 2150);
DISPLAY INVISIBLE (-6025 2150);
FORCEPROP 1 LAST OFFPAGE TRUE
J 0
(-5825 2125);
DISPLAY 0.872340 (-5825 2125);
PAINT GREEN (-5825 2125);
DISPLAY INVISIBLE (-5825 2125);
FORCEPROP 2 LAST CDS_LIB mstr_standard
J 0
(-6150 2250);
PAINT MONO (-6150 2250);
DISPLAY INVISIBLE (-6150 2250);
FORCEADD OFFPAGE..1
(-6150 3500);
FORCEPROP 2 LAST $XR0 129 
J 0
(-6402 3500);
DISPLAY 0.638298 (-6402 3500);
PAINT MONO (-6402 3500);
FORCEPROP 2 LAST PATH I6
J 0
(-6100 3575);
DISPLAY 1.021277 (-6100 3575);
PAINT ORANGE (-6100 3575);
DISPLAY INVISIBLE (-6100 3575);
FORCEPROP 1 LAST COMMENT_BODY TRUE
J 0
(-6025 3400);
DISPLAY 1.170213 (-6025 3400);
PAINT GREEN (-6025 3400);
DISPLAY INVISIBLE (-6025 3400);
FORCEPROP 1 LAST OFFPAGE TRUE
J 0
(-5825 3375);
DISPLAY 1.170213 (-5825 3375);
PAINT GREEN (-5825 3375);
DISPLAY INVISIBLE (-5825 3375);
FORCEPROP 2 LAST CDS_LIB mstr_standard
J 0
(-6150 3500);
PAINT MONO (-6150 3500);
DISPLAY INVISIBLE (-6150 3500);
FORCEADD VCC_CORE..1
(-1075 2275);
FORCEPROP 3 LASTPIN (-1075 2225) SIG_NAME PVCCMCP_CPU0\g
J 0
(-1065 2235);
DISPLAY 0.659574 (-1065 2235);
PAINT MONO (-1065 2235);
DISPLAY INVISIBLE (-1065 2235);
FORCEPROP 1 LAST HDL_POWER PVCCMCP_CPU0
J 1
(-1075 2325);
DISPLAY 0.617021 (-1075 2325);
PAINT GREEN (-1075 2325);
FORCEPROP 1 LAST PATH I60
J 0
(-1025 2300);
DISPLAY 0.872340 (-1025 2300);
PAINT AQUA (-1025 2300);
DISPLAY INVISIBLE (-1025 2300);
FORCEPROP 2 LAST CDS_LIB mstr_symbols
J 0
(-1075 2275);
PAINT ORANGE (-1075 2275);
DISPLAY INVISIBLE (-1075 2275);
FORCEADD SKX_EXT_B..9
(-3900 2550);
FORCEPROP 1 LAST LOCATION U5D1
J 0
(-4800 3700);
DISPLAY 0.617021 (-4800 3700);
PAINT AQUA (-4800 3700);
FORCEPROP 1 LAST PART_NUMBER TBD
J 0
(-4800 1400);
DISPLAY 0.617021 (-4800 1400);
PAINT BLUE (-4800 1400);
FORCEPROP 2 LASTPIN (-2950 2150) $PN AR20
J 0
(-2940 2160);
DISPLAY 0.617021 (-2940 2160);
PAINT ORANGE (-2940 2160);
FORCEPROP 2 LASTPIN (-2950 2100) $PN AR22
J 0
(-2940 2110);
DISPLAY 0.617021 (-2940 2110);
PAINT ORANGE (-2940 2110);
FORCEPROP 2 LASTPIN (-2950 2000) $PN AR26
J 0
(-2940 2010);
DISPLAY 0.617021 (-2940 2010);
PAINT ORANGE (-2940 2010);
FORCEPROP 2 LASTPIN (-2950 1950) $PN AR62
J 0
(-2940 1960);
DISPLAY 0.617021 (-2940 1960);
PAINT ORANGE (-2940 1960);
FORCEPROP 2 LASTPIN (-2950 1900) $PN AT13
J 0
(-2940 1910);
DISPLAY 0.617021 (-2940 1910);
PAINT ORANGE (-2940 1910);
FORCEPROP 2 LASTPIN (-2950 1850) $PN AT23
J 0
(-2940 1860);
DISPLAY 0.617021 (-2940 1860);
PAINT ORANGE (-2940 1860);
FORCEPROP 2 LASTPIN (-2950 1800) $PN AT25
J 0
(-2940 1810);
DISPLAY 0.617021 (-2940 1810);
PAINT ORANGE (-2940 1810);
FORCEPROP 2 LASTPIN (-2950 1750) $PN AV77
J 0
(-2940 1760);
DISPLAY 0.617021 (-2940 1760);
PAINT ORANGE (-2940 1760);
FORCEPROP 2 LASTPIN (-2950 1700) $PN AW64
J 0
(-2940 1710);
DISPLAY 0.617021 (-2940 1710);
PAINT ORANGE (-2940 1710);
FORCEPROP 2 LASTPIN (-4850 2150) $PN AW76
J 2
(-4860 2160);
DISPLAY 0.617021 (-4860 2160);
PAINT ORANGE (-4860 2160);
FORCEPROP 2 LASTPIN (-4850 2100) $PN AY65
J 2
(-4860 2110);
DISPLAY 0.617021 (-4860 2110);
PAINT ORANGE (-4860 2110);
FORCEPROP 2 LASTPIN (-4850 2000) $PN AY67
J 2
(-4860 2010);
DISPLAY 0.617021 (-4860 2010);
PAINT ORANGE (-4860 2010);
FORCEPROP 2 LASTPIN (-4850 1950) $PN AY75
J 2
(-4860 1960);
DISPLAY 0.617021 (-4860 1960);
PAINT ORANGE (-4860 1960);
FORCEPROP 2 LASTPIN (-4850 1900) $PN AY77
J 2
(-4860 1910);
DISPLAY 0.617021 (-4860 1910);
PAINT ORANGE (-4860 1910);
FORCEPROP 2 LASTPIN (-4850 1850) $PN BA14
J 2
(-4860 1860);
DISPLAY 0.617021 (-4860 1860);
PAINT ORANGE (-4860 1860);
FORCEPROP 2 LASTPIN (-4850 1800) $PN BA16
J 2
(-4860 1810);
DISPLAY 0.617021 (-4860 1810);
PAINT ORANGE (-4860 1810);
FORCEPROP 2 LASTPIN (-4850 1750) $PN BA18
J 2
(-4860 1760);
DISPLAY 0.617021 (-4860 1760);
PAINT ORANGE (-4860 1760);
FORCEPROP 2 LASTPIN (-4850 1700) $PN BA22
J 2
(-4860 1710);
DISPLAY 0.617021 (-4860 1710);
PAINT ORANGE (-4860 1710);
FORCEPROP 2 LASTPIN (-4850 1650) $PN BA64
J 2
(-4860 1660);
DISPLAY 0.617021 (-4860 1660);
PAINT ORANGE (-4860 1660);
FORCEPROP 2 LASTPIN (-2950 1650) $PN BA66
J 0
(-2940 1660);
DISPLAY 0.617021 (-2940 1660);
PAINT ORANGE (-2940 1660);
FORCEPROP 2 LASTPIN (-2950 1600) $PN BA76
J 0
(-2940 1610);
DISPLAY 0.617021 (-2940 1610);
PAINT ORANGE (-2940 1610);
FORCEPROP 2 LASTPIN (-2950 3450) $PN CR4
J 0
(-2940 3460);
DISPLAY 0.617021 (-2940 3460);
PAINT ORANGE (-2940 3460);
FORCEPROP 2 LASTPIN (-2950 3400) $PN CM3
J 0
(-2940 3410);
DISPLAY 0.617021 (-2940 3410);
PAINT ORANGE (-2940 3410);
FORCEPROP 2 LASTPIN (-2950 3350) $PN CL4
J 0
(-2940 3360);
DISPLAY 0.617021 (-2940 3360);
PAINT ORANGE (-2940 3360);
FORCEPROP 2 LASTPIN (-2950 3300) $PN CH5
J 0
(-2940 3310);
DISPLAY 0.617021 (-2940 3310);
PAINT ORANGE (-2940 3310);
FORCEPROP 2 LASTPIN (-2950 3150) $PN CN4
J 0
(-2940 3160);
DISPLAY 0.617021 (-2940 3160);
PAINT ORANGE (-2940 3160);
FORCEPROP 2 LASTPIN (-2950 3100) $PN CJ4
J 0
(-2940 3110);
DISPLAY 0.617021 (-2940 3110);
PAINT ORANGE (-2940 3110);
FORCEPROP 2 LASTPIN (-2950 3050) $PN CG4
J 0
(-2940 3060);
DISPLAY 0.617021 (-2940 3060);
PAINT ORANGE (-2940 3060);
FORCEPROP 2 LASTPIN (-4850 3450) $PN CV11
J 2
(-4860 3460);
DISPLAY 0.617021 (-4860 3460);
PAINT ORANGE (-4860 3460);
FORCEPROP 2 LASTPIN (-4850 3400) $PN CP11
J 2
(-4860 3410);
DISPLAY 0.617021 (-4860 3410);
PAINT ORANGE (-4860 3410);
FORCEPROP 2 LASTPIN (-4850 3350) $PN CN10
J 2
(-4860 3360);
DISPLAY 0.617021 (-4860 3360);
PAINT ORANGE (-4860 3360);
FORCEPROP 2 LASTPIN (-4850 3300) $PN CL10
J 2
(-4860 3310);
DISPLAY 0.617021 (-4860 3310);
PAINT ORANGE (-4860 3310);
FORCEPROP 2 LASTPIN (-4850 3200) $PN CT11
J 2
(-4860 3210);
DISPLAY 0.617021 (-4860 3210);
PAINT ORANGE (-4860 3210);
FORCEPROP 2 LASTPIN (-4850 3150) $PN CR12
J 2
(-4860 3160);
DISPLAY 0.617021 (-4860 3160);
PAINT ORANGE (-4860 3160);
FORCEPROP 2 LASTPIN (-4850 3100) $PN CM11
J 2
(-4860 3110);
DISPLAY 0.617021 (-4860 3110);
PAINT ORANGE (-4860 3110);
FORCEPROP 2 LASTPIN (-4850 3050) $PN CK9
J 2
(-4860 3060);
DISPLAY 0.617021 (-4860 3060);
PAINT ORANGE (-4860 3060);
FORCEPROP 2 LASTPIN (-4850 2250) $PN CD23
J 2
(-4860 2260);
DISPLAY 0.617021 (-4860 2260);
PAINT ORANGE (-4860 2260);
FORCEPROP 2 LASTPIN (-4850 2300) $PN CE24
J 2
(-4860 2310);
DISPLAY 0.617021 (-4860 2310);
PAINT ORANGE (-4860 2310);
FORCEPROP 2 LASTPIN (-2950 2250) $PN CC22
J 0
(-2940 2260);
DISPLAY 0.617021 (-2940 2260);
PAINT ORANGE (-2940 2260);
FORCEPROP 2 LASTPIN (-4850 2350) $PN BY21
J 2
(-4860 2360);
DISPLAY 0.617021 (-4860 2360);
PAINT ORANGE (-4860 2360);
FORCEPROP 2 LASTPIN (-4850 2400) $PN CB23
J 2
(-4860 2410);
DISPLAY 0.617021 (-4860 2410);
PAINT ORANGE (-4860 2410);
FORCEPROP 2 LASTPIN (-2950 2350) $PN CF25
J 0
(-2940 2360);
DISPLAY 0.617021 (-2940 2360);
PAINT ORANGE (-2940 2360);
FORCEPROP 2 LASTPIN (-2950 2950) $PN BW24
J 0
(-2940 2960);
DISPLAY 0.617021 (-2940 2960);
PAINT ORANGE (-2940 2960);
FORCEPROP 2 LASTPIN (-2950 2900) $PN BU24
J 0
(-2940 2910);
DISPLAY 0.617021 (-2940 2910);
PAINT ORANGE (-2940 2910);
FORCEPROP 2 LASTPIN (-4850 2950) $PN BG16
J 2
(-4860 2960);
DISPLAY 0.617021 (-4860 2960);
PAINT ORANGE (-4860 2960);
FORCEPROP 2 LASTPIN (-4850 2900) $PN BE16
J 2
(-4860 2910);
DISPLAY 0.617021 (-4860 2910);
PAINT ORANGE (-4860 2910);
FORCEPROP 2 LASTPIN (-2950 2800) $PN BK23
J 0
(-2940 2810);
DISPLAY 0.617021 (-2940 2810);
PAINT ORANGE (-2940 2810);
FORCEPROP 2 LASTPIN (-2950 2750) $PN BT19
J 0
(-2940 2760);
DISPLAY 0.617021 (-2940 2760);
PAINT ORANGE (-2940 2760);
FORCEPROP 2 LASTPIN (-2950 2700) $PN BM23
J 0
(-2940 2710);
DISPLAY 0.617021 (-2940 2710);
PAINT ORANGE (-2940 2710);
FORCEPROP 2 LASTPIN (-2950 2650) $PN BM21
J 0
(-2940 2660);
DISPLAY 0.617021 (-2940 2660);
PAINT ORANGE (-2940 2660);
FORCEPROP 2 LASTPIN (-2950 2500) $PN BH23
J 0
(-2940 2510);
DISPLAY 0.617021 (-2940 2510);
PAINT ORANGE (-2940 2510);
FORCEPROP 2 LASTPIN (-2950 2550) $PN BJ22
J 0
(-2940 2560);
DISPLAY 0.617021 (-2940 2560);
PAINT ORANGE (-2940 2560);
FORCEPROP 2 LASTPIN (-4850 2800) $PN BN24
J 2
(-4860 2810);
DISPLAY 0.617021 (-4860 2810);
PAINT ORANGE (-4860 2810);
FORCEPROP 2 LASTPIN (-4850 2750) $PN BR20
J 2
(-4860 2760);
DISPLAY 0.617021 (-4860 2760);
PAINT ORANGE (-4860 2760);
FORCEPROP 2 LASTPIN (-4850 2700) $PN BK21
J 2
(-4860 2710);
DISPLAY 0.617021 (-4860 2710);
PAINT ORANGE (-4860 2710);
FORCEPROP 2 LASTPIN (-4850 2650) $PN BP19
J 2
(-4860 2660);
DISPLAY 0.617021 (-4860 2660);
PAINT ORANGE (-4860 2660);
FORCEPROP 2 LASTPIN (-4850 2500) $PN BP23
J 2
(-4860 2510);
DISPLAY 0.617021 (-4860 2510);
PAINT ORANGE (-4860 2510);
FORCEPROP 2 LASTPIN (-4850 2550) $PN BN22
J 2
(-4860 2560);
DISPLAY 0.617021 (-4860 2560);
PAINT ORANGE (-4860 2560);
FORCEPROP 1 LAST MATERIAL IC
J 0
(-4800 3650);
DISPLAY 0.617021 (-4800 3650);
PAINT SKYBLUE (-4800 3650);
FORCEPROP 2 LASTPIN (-2950 3200) $PN CP5
J 0
(-2940 3210);
DISPLAY 0.617021 (-2940 3210);
PAINT ORANGE (-2940 3210);
FORCEPROP 1 LAST PACK_TYPE BGA1
J 0
(-4800 3750);
PAINT SKYBLUE (-4800 3750);
DISPLAY INVISIBLE (-4800 3750);
FORCEPROP 2 LAST CDS_LIB chpset_lib
J 0
(-3900 2550);
PAINT ORANGE (-3900 2550);
DISPLAY INVISIBLE (-3900 2550);
FORCEPROP 2 LAST SEC_TYPE BGA1
J 0
(-4800 3750);
DISPLAY 1.021277 (-4800 3750);
PAINT ORANGE (-4800 3750);
DISPLAY INVISIBLE (-4800 3750);
FORCEPROP 2 LAST SEC 9
J 0
(-4800 3750);
DISPLAY 0.680851 (-4800 3750);
PAINT MONO (-4800 3750);
DISPLAY INVISIBLE (-4800 3750);
FORCEPROP 2 LAST CDS_LOCATION U5D1
J 0
(-4800 3700);
DISPLAY 0.617021 (-4800 3700);
PAINT AQUA (-4800 3700);
DISPLAY INVISIBLE (-4800 3700);
FORCEPROP 1 LAST PATH I61
J 0
(-3900 3650);
PAINT GREEN (-3900 3650);
DISPLAY INVISIBLE (-3900 3650);
FORCEPROP 0 LAST ROOM CPU0
J 0
(-4800 3800);
DISPLAY 1.021277 (-4800 3800);
PAINT ORANGE (-4800 3800);
DISPLAY INVISIBLE (-4800 3800);
FORCEADD TAP..1
R 2
(-5050 3050);
FORCEPROP 3 LASTPIN (-5000 3050) SIG_NAME DMI_CPU0_PCH_RX_C_DN<0>
J 0
(-4990 3060);
DISPLAY 0.659574 (-4990 3060);
PAINT MONO (-4990 3060);
DISPLAY INVISIBLE (-4990 3060);
FORCEPROP 1 LASTPIN (-5000 3050) BN 0
J 2
(-4988 3058);
DISPLAY 0.617021 (-4988 3058);
PAINT PINK (-4988 3058);
FORCEPROP 2 LAST CDS_LIB mstr_standard
J 0
(-5050 3050);
PAINT MONO (-5050 3050);
DISPLAY INVISIBLE (-5050 3050);
FORCEPROP 1 LAST BODY_TYPE PLUMBING
J 2
(-5050 3100);
DISPLAY 1.446809 (-5050 3100);
PAINT GREEN (-5050 3100);
DISPLAY INVISIBLE (-5050 3100);
FORCEPROP 1 LAST HDL_TAP TRUE
J 2
(-5375 2925);
DISPLAY 1.446809 (-5375 2925);
PAINT GREEN (-5375 2925);
DISPLAY INVISIBLE (-5375 2925);
FORCEPROP 1 LAST PATH I7
J 2
(-5048 3050);
DISPLAY 0.872340 (-5048 3050);
PAINT GREEN (-5048 3050);
DISPLAY INVISIBLE (-5048 3050);
FORCEADD TAP..1
R 2
(-5050 3100);
FORCEPROP 3 LASTPIN (-5000 3100) SIG_NAME DMI_CPU0_PCH_RX_C_DN<1>
J 0
(-4990 3110);
DISPLAY 0.659574 (-4990 3110);
PAINT MONO (-4990 3110);
DISPLAY INVISIBLE (-4990 3110);
FORCEPROP 1 LASTPIN (-5000 3100) BN 1
J 2
(-4988 3108);
DISPLAY 0.617021 (-4988 3108);
PAINT PINK (-4988 3108);
FORCEPROP 2 LAST CDS_LIB mstr_standard
J 0
(-5050 3100);
PAINT MONO (-5050 3100);
DISPLAY INVISIBLE (-5050 3100);
FORCEPROP 1 LAST BODY_TYPE PLUMBING
J 2
(-5050 3150);
DISPLAY 1.446809 (-5050 3150);
PAINT GREEN (-5050 3150);
DISPLAY INVISIBLE (-5050 3150);
FORCEPROP 1 LAST HDL_TAP TRUE
J 2
(-5375 2975);
DISPLAY 1.446809 (-5375 2975);
PAINT GREEN (-5375 2975);
DISPLAY INVISIBLE (-5375 2975);
FORCEPROP 1 LAST PATH I8
J 2
(-5048 3100);
DISPLAY 0.872340 (-5048 3100);
PAINT GREEN (-5048 3100);
DISPLAY INVISIBLE (-5048 3100);
FORCEADD TAP..1
R 2
(-5050 3200);
FORCEPROP 3 LASTPIN (-5000 3200) SIG_NAME DMI_CPU0_PCH_RX_C_DN<3>
J 0
(-4990 3210);
DISPLAY 0.659574 (-4990 3210);
PAINT MONO (-4990 3210);
DISPLAY INVISIBLE (-4990 3210);
FORCEPROP 1 LASTPIN (-5000 3200) BN 3
J 2
(-4988 3208);
DISPLAY 0.617021 (-4988 3208);
PAINT PINK (-4988 3208);
FORCEPROP 2 LAST CDS_LIB mstr_standard
J 0
(-5050 3200);
PAINT MONO (-5050 3200);
DISPLAY INVISIBLE (-5050 3200);
FORCEPROP 1 LAST BODY_TYPE PLUMBING
J 2
(-5050 3250);
DISPLAY 1.446809 (-5050 3250);
PAINT GREEN (-5050 3250);
DISPLAY INVISIBLE (-5050 3250);
FORCEPROP 1 LAST HDL_TAP TRUE
J 2
(-5375 3075);
DISPLAY 1.446809 (-5375 3075);
PAINT GREEN (-5375 3075);
DISPLAY INVISIBLE (-5375 3075);
FORCEPROP 1 LAST PATH I9
J 2
(-5048 3200);
DISPLAY 0.872340 (-5048 3200);
PAINT GREEN (-5048 3200);
DISPLAY INVISIBLE (-5048 3200);
FORCEADD DESIGN_NOTE..1
(-4625 1250);
FORCEPROP 0 LAST L1 CPU SYMBOLS 1-30 ARE PRELIMINARY AND SUBJECT TO CHANGE
J 0
(-4825 1125);
DISPLAY 1.021277 (-4825 1125);
PAINT ORANGE (-4825 1125);
FORCEPROP 1 LAST COMMENT_BODY TRUE
J 0
(-4600 1350);
DISPLAY 0.978723 (-4600 1350);
PAINT ORANGE (-4600 1350);
DISPLAY INVISIBLE (-4600 1350);
FORCEPROP 2 LAST CDS_LIB mstr_symbols
J 0
(-4625 1250);
PAINT ORANGE (-4625 1250);
DISPLAY INVISIBLE (-4625 1250);
FORCEADD PRELIM..10
(-3890 2590);
PAINT GRAY (-3890 2590);
FORCEPROP 1 LAST COMMENT_BODY TRUE
J 0
(-3890 2590);
PAINT ORANGE (-3890 2590);
DISPLAY INVISIBLE (-3890 2590);
FORCEPROP 2 LAST CDS_LIB mstr_misc
J 0
(-3890 2590);
PAINT ORANGE (-3890 2590);
DISPLAY INVISIBLE (-3890 2590);
FORCEADD INTEL_CORP_BPAGE..1
(0 0);
FORCEPROP 1 LAST CDS_CON_LAST_MODIFIED Fri Jun 16 17:48:12 2017
J 0
(-1425 325);
DISPLAY 1.340426 (-1425 325);
PAINT GREEN (-1425 325);
DISPLAY INVISIBLE (-1425 325);
FORCEPROP 1 LAST CUSTOM_TXT_CDS <CURRENT_DESIGN_SHEET> OF <TOTAL_DESIGN_SHEETS>
J 0
(-500 25);
PAINT ORANGE (-500 25);
FORCEPROP 1 LAST CUSTOM_TXT_CDS <CON_LAST_MODIFIED>
J 0
(-4000 100);
PAINT ORANGE (-4000 100);
FORCEPROP 2 LAST CUSTOM_TXT_CDS <XR_PAGE_TITLE>
J 0
(-7890 5250);
DISPLAY 0.638298 (-7890 5250);
PAINT PINK (-7890 5250);
DISPLAY INVISIBLE (-7890 5250);
FORCEPROP 1 LAST SCH_TITLE SKYLAKE - SKT0 - 9 OF 21
J 0
(-7950 50);
DISPLAY 1.212766 (-7950 50);
PAINT GREEN (-7950 50);
FORCEPROP 1 LAST COMMENT_BODY TRUE
J 0
(12 12);
DISPLAY 0.638298 (12 12);
PAINT GREEN (12 12);
DISPLAY INVISIBLE (12 12);
FORCEPROP 2 LAST PAGE_BORDER TRUE
J 0
(-7890 5250);
DISPLAY 0.851064 (-7890 5250);
PAINT PINK (-7890 5250);
DISPLAY INVISIBLE (-7890 5250);
FORCEPROP 2 LAST CDS_LIB mstr_symbols
J 0
(0 0);
PAINT ORANGE (0 0);
DISPLAY INVISIBLE (0 0);
FORCEPROP 2 LAST CDS_XR_PAGE_TITLE CR-29 : @BASEBOARD_FAB2_LIB.BASEBOARD_FAB2(SCH_1):PAGE29
J 0
(-7890 5250);
DISPLAY 0.638298 (-7890 5250);
PAINT PINK (-7890 5250);
DISPLAY INVISIBLE (-7890 5250);
WIRE 16 -1 (-1075 2150)(-1075 2225);
WIRE 16 -1 (-1075 1850)(-1075 2150);
WIRE 16 -1 (-2800 2150)(-1075 2150);
WIRE 16 -1 (-2800 2100)(-2800 2150);
WIRE 16 -1 (-2950 2150)(-2800 2150);
WIRE 16 -1 (-2800 1850)(-1075 1850);
WIRE 16 -1 (-2800 1800)(-2800 1850);
WIRE 16 -1 (-2950 1850)(-2800 1850);
WIRE 16 -1 (-2800 2000)(-2800 2100);
WIRE 16 -1 (-2950 2100)(-2800 2100);
WIRE 16 -1 (-2950 2000)(-2800 2000);
WIRE 16 -1 (-2950 1800)(-2800 1800);
WIRE 17 -1 (-2700 3500)(-1700 3500);
FORCEPROP 2 LAST SIG_NAME DMI_CPU0_PCH_TX_DP<3:0>
J 0
(-2660 3510);
DISPLAY 0.617021 (-2660 3510);
PAINT ORANGE (-2660 3510);
WIRE 17 -1 (-2700 3500)(-2700 3475);
WIRE 17 -1 (-2700 3425)(-2700 3475);
WIRE 17 -1 (-2700 3375)(-2700 3425);
WIRE 17 -1 (-2700 3325)(-2700 3375);
WIRE 17 -1 (-2700 3250)(-1700 3250);
FORCEPROP 2 LAST SIG_NAME DMI_CPU0_PCH_TX_DN<3:0>
J 0
(-2635 3260);
DISPLAY 0.617021 (-2635 3260);
PAINT ORANGE (-2635 3260);
WIRE 17 -1 (-2700 3250)(-2700 3225);
WIRE 17 -1 (-2700 3175)(-2700 3225);
WIRE 17 -1 (-2700 3125)(-2700 3175);
WIRE 17 -1 (-2700 3075)(-2700 3125);
WIRE 17 -1 (-6100 3500)(-5100 3500);
FORCEPROP 2 LAST SIG_NAME DMI_CPU0_PCH_RX_C_DP<3:0>
J 0
(-6035 3510);
DISPLAY 0.617021 (-6035 3510);
PAINT ORANGE (-6035 3510);
WIRE 17 -1 (-5100 3500)(-5100 3475);
WIRE 17 -1 (-5100 3475)(-5100 3425);
WIRE 17 -1 (-5100 3425)(-5100 3375);
WIRE 17 -1 (-5100 3375)(-5100 3325);
WIRE 17 -1 (-6100 3250)(-5100 3250);
FORCEPROP 2 LAST SIG_NAME DMI_CPU0_PCH_RX_C_DN<3:0>
J 0
(-6035 3260);
DISPLAY 0.617021 (-6035 3260);
PAINT ORANGE (-6035 3260);
WIRE 17 -1 (-5100 3250)(-5100 3225);
WIRE 17 -1 (-5100 3225)(-5100 3175);
WIRE 17 -1 (-5100 3175)(-5100 3125);
WIRE 17 -1 (-5100 3125)(-5100 3075);
WIRE 16 -1 (-1700 1750)(-2950 1750);
FORCEPROP 2 LAST SIG_NAME TP_CPU0_RSVD_186
J 0
(-2625 1760);
DISPLAY 0.617021 (-2625 1760);
PAINT ORANGE (-2625 1760);
FORCEPROP 2 LASTPROP $XRERR UNIQUE?
J 0
(-1670 1750);
DISPLAY 0.638298 (-1670 1750);
PAINT MONO (-1670 1750);
DISPLAY INVISIBLE (-1670 1750);
WIRE 16 -1 (-6100 2900)(-4850 2900);
FORCEPROP 2 LAST SIG_NAME CLK_156M_OSC_CPU0_HFI_DN
J 0
(-6035 2910);
DISPLAY 0.617021 (-6035 2910);
PAINT ORANGE (-6035 2910);
WIRE 16 -1 (-1700 2550)(-2950 2550);
FORCEPROP 2 LAST SIG_NAME SMB_HFI1_CPU0_LVC2_SCL
J 0
(-2625 2560);
DISPLAY 0.617021 (-2625 2560);
PAINT ORANGE (-2625 2560);
WIRE 16 -1 (-1700 2500)(-2950 2500);
FORCEPROP 2 LAST SIG_NAME SMB_HFI1_CPU0_LVC2_SDA
J 0
(-2625 2510);
DISPLAY 0.617021 (-2625 2510);
PAINT ORANGE (-2625 2510);
WIRE 16 -1 (-1700 2350)(-2950 2350);
FORCEPROP 2 LAST SIG_NAME RST_CD_CPU0_POR_N
J 0
(-2625 2360);
DISPLAY 0.617021 (-2625 2360);
PAINT ORANGE (-2625 2360);
WIRE 16 -1 (-1700 2250)(-2950 2250);
FORCEPROP 2 LAST SIG_NAME JTAG_MCP_CPU0_TDO
J 0
(-2610 2260);
DISPLAY 0.617021 (-2610 2260);
PAINT ORANGE (-2610 2260);
WIRE 16 -1 (-1700 2750)(-2950 2750);
FORCEPROP 2 LAST SIG_NAME FM_MODPRST_HFI1_CPU0_LVT2_N
J 0
(-2625 2760);
DISPLAY 0.617021 (-2625 2760);
PAINT ORANGE (-2625 2760);
WIRE 16 -1 (-1700 2700)(-2950 2700);
FORCEPROP 2 LAST SIG_NAME LED_HFI1_CPU0_N
J 0
(-2625 2710);
DISPLAY 0.617021 (-2625 2710);
PAINT ORANGE (-2625 2710);
WIRE 16 -1 (-4850 2950)(-6100 2950);
FORCEPROP 2 LAST SIG_NAME CLK_156M_OSC_CPU0_HFI_DP
J 0
(-6035 2960);
DISPLAY 0.617021 (-6035 2960);
PAINT ORANGE (-6035 2960);
WIRE 16 -1 (-4850 2100)(-6100 2100);
FORCEPROP 2 LAST SIG_NAME TP_CPU0_RSVD_182
J 0
(-6050 2110);
DISPLAY 0.617021 (-6050 2110);
PAINT ORANGE (-6050 2110);
FORCEPROP 2 LASTPROP $XRERR UNIQUE?
J 0
(-6340 2100);
DISPLAY 0.638298 (-6340 2100);
PAINT MONO (-6340 2100);
DISPLAY INVISIBLE (-6340 2100);
WIRE 16 -1 (-4850 2150)(-6100 2150);
FORCEPROP 2 LAST SIG_NAME TP_CPU0_RSVD_183
J 0
(-6050 2160);
DISPLAY 0.617021 (-6050 2160);
PAINT ORANGE (-6050 2160);
FORCEPROP 2 LASTPROP $XRERR UNIQUE?
J 0
(-6340 2150);
DISPLAY 0.638298 (-6340 2150);
PAINT MONO (-6340 2150);
DISPLAY INVISIBLE (-6340 2150);
WIRE 16 -1 (-4850 1650)(-6100 1650);
FORCEPROP 2 LAST SIG_NAME TP_CPU0_RSVD_174
J 0
(-6050 1660);
DISPLAY 0.617021 (-6050 1660);
PAINT ORANGE (-6050 1660);
FORCEPROP 2 LASTPROP $XRERR UNIQUE?
J 0
(-6340 1650);
DISPLAY 0.638298 (-6340 1650);
PAINT MONO (-6340 1650);
DISPLAY INVISIBLE (-6340 1650);
WIRE 16 -1 (-4850 1700)(-6100 1700);
FORCEPROP 2 LAST SIG_NAME TP_CPU0_RSVD_175
J 0
(-6050 1710);
DISPLAY 0.617021 (-6050 1710);
PAINT ORANGE (-6050 1710);
FORCEPROP 2 LASTPROP $XRERR UNIQUE?
J 0
(-6340 1700);
DISPLAY 0.638298 (-6340 1700);
PAINT MONO (-6340 1700);
DISPLAY INVISIBLE (-6340 1700);
WIRE 16 -1 (-4850 1750)(-6100 1750);
FORCEPROP 2 LAST SIG_NAME TP_CPU0_RSVD_176
J 0
(-6050 1760);
DISPLAY 0.617021 (-6050 1760);
PAINT ORANGE (-6050 1760);
FORCEPROP 2 LASTPROP $XRERR UNIQUE?
J 0
(-6340 1750);
DISPLAY 0.638298 (-6340 1750);
PAINT MONO (-6340 1750);
DISPLAY INVISIBLE (-6340 1750);
WIRE 16 -1 (-4850 1800)(-6100 1800);
FORCEPROP 2 LAST SIG_NAME TP_CPU0_RSVD_177
J 0
(-6050 1810);
DISPLAY 0.617021 (-6050 1810);
PAINT ORANGE (-6050 1810);
FORCEPROP 2 LASTPROP $XRERR UNIQUE?
J 0
(-6340 1800);
DISPLAY 0.638298 (-6340 1800);
PAINT MONO (-6340 1800);
DISPLAY INVISIBLE (-6340 1800);
WIRE 16 -1 (-4850 1850)(-6100 1850);
FORCEPROP 2 LAST SIG_NAME TP_CPU0_RSVD_178
J 0
(-6050 1860);
DISPLAY 0.617021 (-6050 1860);
PAINT ORANGE (-6050 1860);
FORCEPROP 2 LASTPROP $XRERR UNIQUE?
J 0
(-6340 1850);
DISPLAY 0.638298 (-6340 1850);
PAINT MONO (-6340 1850);
DISPLAY INVISIBLE (-6340 1850);
WIRE 16 -1 (-4850 1900)(-6100 1900);
FORCEPROP 2 LAST SIG_NAME TP_CPU0_RSVD_179
J 0
(-6050 1910);
DISPLAY 0.617021 (-6050 1910);
PAINT ORANGE (-6050 1910);
FORCEPROP 2 LASTPROP $XRERR UNIQUE?
J 0
(-6340 1900);
DISPLAY 0.638298 (-6340 1900);
PAINT MONO (-6340 1900);
DISPLAY INVISIBLE (-6340 1900);
WIRE 16 -1 (-4850 1950)(-6100 1950);
FORCEPROP 2 LAST SIG_NAME TP_CPU0_RSVD_180
J 0
(-6050 1960);
DISPLAY 0.617021 (-6050 1960);
PAINT ORANGE (-6050 1960);
FORCEPROP 2 LASTPROP $XRERR UNIQUE?
J 0
(-6340 1950);
DISPLAY 0.638298 (-6340 1950);
PAINT MONO (-6340 1950);
DISPLAY INVISIBLE (-6340 1950);
WIRE 16 -1 (-4850 2000)(-6100 2000);
FORCEPROP 2 LAST SIG_NAME TP_CPU0_RSVD_181
J 0
(-6050 2010);
DISPLAY 0.617021 (-6050 2010);
PAINT ORANGE (-6050 2010);
FORCEPROP 2 LASTPROP $XRERR UNIQUE?
J 0
(-6340 2000);
DISPLAY 0.638298 (-6340 2000);
PAINT MONO (-6340 2000);
DISPLAY INVISIBLE (-6340 2000);
WIRE 16 -1 (-6100 2550)(-4850 2550);
FORCEPROP 2 LAST SIG_NAME SMB_HFI0_CPU0_LVC2_SCL
J 0
(-6025 2560);
DISPLAY 0.617021 (-6025 2560);
PAINT ORANGE (-6025 2560);
WIRE 16 -1 (-4850 2500)(-6100 2500);
FORCEPROP 2 LAST SIG_NAME SMB_HFI0_CPU0_LVC2_SDA
J 0
(-6025 2510);
DISPLAY 0.617021 (-6025 2510);
PAINT ORANGE (-6025 2510);
WIRE 16 -1 (-6100 2650)(-4850 2650);
FORCEPROP 2 LAST SIG_NAME IRQ_HFI0_CPU0_LVT2_N
J 0
(-6025 2660);
DISPLAY 0.617021 (-6025 2660);
PAINT ORANGE (-6025 2660);
WIRE 16 -1 (-6100 2700)(-4850 2700);
FORCEPROP 2 LAST SIG_NAME LED_HFI0_CPU0_N
J 0
(-6025 2710);
DISPLAY 0.617021 (-6025 2710);
PAINT ORANGE (-6025 2710);
WIRE 16 -1 (-4850 2750)(-6100 2750);
FORCEPROP 2 LAST SIG_NAME FM_MODPRST_HFI0_CPU0_LVT2_N
J 0
(-6025 2760);
DISPLAY 0.617021 (-6025 2760);
PAINT ORANGE (-6025 2760);
WIRE 16 -1 (-4850 2800)(-6100 2800);
FORCEPROP 2 LAST SIG_NAME RST_HFI0_CPU0_LVT2_N
J 0
(-6025 2810);
DISPLAY 0.617021 (-6025 2810);
PAINT ORANGE (-6025 2810);
WIRE 16 -1 (-1700 2650)(-2950 2650);
FORCEPROP 2 LAST SIG_NAME IRQ_HFI1_CPU0_LVT2_N
J 0
(-2625 2660);
DISPLAY 0.617021 (-2625 2660);
PAINT ORANGE (-2625 2660);
WIRE 16 -1 (-1700 2800)(-2950 2800);
FORCEPROP 2 LAST SIG_NAME RST_HFI1_CPU0_LVT2_N
J 0
(-2625 2810);
DISPLAY 0.617021 (-2625 2810);
PAINT ORANGE (-2625 2810);
WIRE 16 -1 (-1700 2900)(-2950 2900);
FORCEPROP 2 LAST SIG_NAME CLK_100M_CPU0_PE_REFCLK_DN
J 0
(-2625 2910);
DISPLAY 0.617021 (-2625 2910);
PAINT ORANGE (-2625 2910);
WIRE 16 -1 (-1700 2950)(-2950 2950);
FORCEPROP 2 LAST SIG_NAME CLK_100M_CPU0_PE_REFCLK_DP
J 0
(-2625 2960);
DISPLAY 0.617021 (-2625 2960);
PAINT ORANGE (-2625 2960);
WIRE 16 -1 (-6100 2400)(-4850 2400);
FORCEPROP 2 LAST SIG_NAME JTAG_MCP_TCK
J 0
(-6035 2410);
DISPLAY 0.617021 (-6035 2410);
PAINT ORANGE (-6035 2410);
WIRE 16 -1 (-4850 2350)(-6100 2350);
FORCEPROP 2 LAST SIG_NAME JTAG_MCP_CPU0_TDI
J 0
(-6035 2360);
DISPLAY 0.617021 (-6035 2360);
PAINT ORANGE (-6035 2360);
WIRE 16 -1 (-4850 2300)(-6100 2300);
FORCEPROP 2 LAST SIG_NAME JTAG_MCP_TMS
J 0
(-6035 2310);
DISPLAY 0.617021 (-6035 2310);
PAINT ORANGE (-6035 2310);
WIRE 16 -1 (-4850 2250)(-6100 2250);
FORCEPROP 2 LAST SIG_NAME JTAG_MCP_TRST_N
J 0
(-6035 2260);
DISPLAY 0.617021 (-6035 2260);
PAINT ORANGE (-6035 2260);
WIRE 16 -1 (-4850 3200)(-5000 3200);
WIRE 16 -1 (-5000 3150)(-4850 3150);
WIRE 16 -1 (-4850 3100)(-5000 3100);
WIRE 16 -1 (-4850 3050)(-5000 3050);
WIRE 16 -1 (-5000 3450)(-4850 3450);
WIRE 16 -1 (-5000 3400)(-4850 3400);
WIRE 16 -1 (-5000 3350)(-4850 3350);
WIRE 16 -1 (-4850 3300)(-5000 3300);
WIRE 16 -1 (-2800 3200)(-2950 3200);
WIRE 16 -1 (-2800 3150)(-2950 3150);
WIRE 16 -1 (-2800 3100)(-2950 3100);
WIRE 16 -1 (-2800 3050)(-2950 3050);
WIRE 16 -1 (-2800 3450)(-2950 3450);
WIRE 16 -1 (-2950 3400)(-2800 3400);
WIRE 16 -1 (-2800 3350)(-2950 3350);
WIRE 16 -1 (-2800 3300)(-2950 3300);
WIRE 16 -1 (-1700 1950)(-2950 1950);
FORCEPROP 2 LAST SIG_NAME TP_CPU0_RSVD_190
J 0
(-2625 1960);
DISPLAY 0.617021 (-2625 1960);
PAINT ORANGE (-2625 1960);
FORCEPROP 2 LASTPROP $XRERR UNIQUE?
J 0
(-1670 1950);
DISPLAY 0.638298 (-1670 1950);
PAINT MONO (-1670 1950);
DISPLAY INVISIBLE (-1670 1950);
WIRE 16 -1 (-1700 1900)(-2950 1900);
FORCEPROP 2 LAST SIG_NAME TP_CPU0_RSVD_189
J 0
(-2625 1910);
DISPLAY 0.617021 (-2625 1910);
PAINT ORANGE (-2625 1910);
FORCEPROP 2 LASTPROP $XRERR UNIQUE?
J 0
(-1670 1900);
DISPLAY 0.638298 (-1670 1900);
PAINT MONO (-1670 1900);
DISPLAY INVISIBLE (-1670 1900);
WIRE 16 -1 (-1700 1700)(-2950 1700);
FORCEPROP 2 LAST SIG_NAME TP_CPU0_RSVD_184
J 0
(-2625 1710);
DISPLAY 0.617021 (-2625 1710);
PAINT ORANGE (-2625 1710);
FORCEPROP 2 LASTPROP $XRERR UNIQUE?
J 0
(-1670 1700);
DISPLAY 0.638298 (-1670 1700);
PAINT MONO (-1670 1700);
DISPLAY INVISIBLE (-1670 1700);
WIRE 16 -1 (-1700 1650)(-2950 1650);
FORCEPROP 2 LAST SIG_NAME TP_CPU0_RSVD_173
J 0
(-2625 1660);
DISPLAY 0.617021 (-2625 1660);
PAINT ORANGE (-2625 1660);
FORCEPROP 2 LASTPROP $XRERR UNIQUE?
J 0
(-1670 1650);
DISPLAY 0.638298 (-1670 1650);
PAINT MONO (-1670 1650);
DISPLAY INVISIBLE (-1670 1650);
WIRE 16 -1 (-1700 1600)(-2950 1600);
FORCEPROP 2 LAST SIG_NAME TP_CPU0_RSVD_172
J 0
(-2625 1610);
DISPLAY 0.617021 (-2625 1610);
PAINT ORANGE (-2625 1610);
FORCEPROP 2 LASTPROP $XRERR UNIQUE?
J 0
(-1670 1600);
DISPLAY 0.638298 (-1670 1600);
PAINT MONO (-1670 1600);
DISPLAY INVISIBLE (-1670 1600);
DOT 1 (-2800 1850);
DOT 1 (-1075 2150);
DOT 1 (-2800 2150);
DOT 1 (-2800 2100);
FORCENOTE
ROOM=CPU0
(-7925 375) 0;
DISPLAY LEFT (-7925 375);
DISPLAY 1.382979 (-7925 375);
PAINT PURPLE (-7925 375);
FORCENOTE
BOM_COST=PROC_SOCKET
(-7925 250) 0;
DISPLAY LEFT (-7925 250);
DISPLAY 1.382979 (-7925 250);
PAINT PURPLE (-7925 250);
FORCENOTE
SKYLAKE - SKT0 - 9 OF 21
(-1675 150) 0;
DISPLAY LEFT (-1675 150);
DISPLAY 1.021277 (-1675 150);
PAINT RED (-1675 150);
QUIT
